# BASEBOARD_FAB2 (Tioga Pass) — schematic netlist excerpt (pin names and nets, part order shuffled) for the footprints in the layout excerpt that follows; sources: Cadence DE-HDL packaged netlist, KiCad conversion of Wiwynn_Tioga_Pass_MB.brd

C5U4  CAP_A  47UF 4V 20% X5R  pkg 0603V  page 217 : A = PVDDQ_ABC ; B = GND

T1D15  TEST-PAD-12P-1-GP-U  pkg DISCRET-GB1  page 258
  DP  = L3_85OHM_10INCH_DP
  DN  = L3_85OHM_10INCH_DN
  GND(0)  = GND
  GND(1)  = GND
  GND(2)  = GND
  GND(3)  = GND
  GND(4)  = GND
  GND(5)  = GND
  GND(6)  = GND
  GND(7)  = GND
  GND(8)  = GND
  GND(9)  = GND

(kicad_pcb
	(version 20260206)
	(generator "pcbnew")
	(generator_version "10.0")
	(general
		(thickness 1.6)
		(legacy_teardrops no)
	)
	(paper "A4")
	(title_block
		(title "Wiwynn_Tioga_Pass_MB.brd")
		(comment 1 "Tioga Pass / footprints 4575-4576 of 4770")
	)
	(layers
		(0 "F.Cu" signal "TOP")
		(4 "In1.Cu" signal "L2GND")
		(6 "In2.Cu" signal "L3")
		(8 "In3.Cu" signal "L4GND")
		(10 "In4.Cu" signal "L5")
		(12 "In5.Cu" signal "L6GND")
		(14 "In6.Cu" signal "L7VCC")
		(16 "In7.Cu" signal "L8VCC")
		(18 "In8.Cu" signal "L9GND")
		(20 "In9.Cu" signal "L10")
		(22 "In10.Cu" signal "L11GND")
		(24 "In11.Cu" signal "L12")
		(26 "In12.Cu" signal "L13GND")
		(2 "B.Cu" signal "BOTTOM")
		(9 "F.Adhes" user "F.Adhesive")
		(11 "B.Adhes" user "B.Adhesive")
		(13 "F.Paste" user "Package Geometry/Pastemask Top")
		(15 "B.Paste" user "Package Geometry/Pastemask Bottom")
		(5 "F.SilkS" user "Ref Des/Silkscreen Top")
		(7 "B.SilkS" user "Ref Des/Silkscreen Bottom")
		(1 "F.Mask" user "Board Geometry/Soldermask Top")
		(3 "B.Mask" user "Board Geometry/Soldermask Bottom")
		(17 "Dwgs.User" user "User.Drawings")
		(19 "Cmts.User" user "User.Comments")
		(21 "Eco1.User" user "User.Eco1")
		(23 "Eco2.User" user "User.Eco2")
		(25 "Edge.Cuts" user "Board Geometry/Outline")
		(27 "Margin" user)
		(31 "F.CrtYd" user "Package Geometry/Place Bound Top")
		(29 "B.CrtYd" user "Package Geometry/Place Bound Bottom")
		(35 "F.Fab" user "Ref Des/Assembly Top")
		(33 "B.Fab" user "Ref Des/Assembly Bottom")
	)
	(footprint ""
		(layer "B.Cu")
		(at 269.559532 -8.1534 90)
		(property "Reference" "C5U4"
			(at -1.848866 0.752348 90)
			(unlocked yes)
			(layer "B.SilkS")
			(effects
				(font
					(size 1.27 0.9652)
					(thickness 0.1524)
				)
				(justify mirror)
			)
		)
		(property "Value" ""
			(at 0 0 90)
			(layer "B.Fab")
			(effects
				(font
					(size 1.27 1.27)
				)
				(justify mirror)
			)
		)
		(duplicate_pad_numbers_are_jumpers no)
		(fp_rect
			(start 0.500126 1.598422)
			(end -0.500126 -0.201422)
			(stroke
				(width 0)
				(type default)
			)
			(fill no)
			(layer "B.CrtYd")
		)
		(fp_line
			(start 0.500126 -0.201422)
			(end -0.500126 -0.201422)
			(stroke
				(width 0.1)
				(type default)
			)
			(layer "B.Fab")
		)
		(fp_line
			(start -0.500126 -0.201422)
			(end -0.500126 1.598422)
			(stroke
				(width 0.1)
				(type default)
			)
			(layer "B.Fab")
		)
		(fp_line
			(start 0.500126 1.598422)
			(end 0.500126 -0.201422)
			(stroke
				(width 0.1)
				(type default)
			)
			(layer "B.Fab")
		)
		(fp_line
			(start -0.500126 1.598422)
			(end 0.500126 1.598422)
			(stroke
				(width 0.1)
				(type default)
			)
			(layer "B.Fab")
		)
		(pad "1" smd rect
			(at 0 0)
			(size 0.889 0.9906)
			(layers "B.Cu" "B.Mask" "B.Paste")
			(net "PVDDQ_ABC")
		)
		(pad "2" smd rect
			(at 0 1.397)
			(size 0.889 0.9906)
			(layers "B.Cu" "B.Mask" "B.Paste")
			(net "GND")
		)
		(zone
			(layer "B.Cu")
			(hatch none 0.5)
			(connect_pads
				(clearance 0)
			)
			(min_thickness 0.25)
			(keepout
				(tracks allowed)
				(vias not_allowed)
				(pads allowed)
				(copperpour not_allowed)
				(footprints allowed)
			)
			(placement
				(enabled no)
				(sheetname "")
			)
			(fill
				(thermal_gap 0.5)
				(thermal_bridge_width 0.5)
				(island_removal_mode 0)
			)
			(polygon
				(pts
					(xy 270.512032 -8.6487) (xy 270.004032 -8.6487) (xy 270.004032 -7.6581) (xy 270.512032 -7.6581)
				)
			)
		)
		(zone
			(layer "B.Cu")
			(hatch none 0.5)
			(connect_pads
				(clearance 0)
			)
			(min_thickness 0.25)
			(keepout
				(tracks not_allowed)
				(vias allowed)
				(pads allowed)
				(copperpour not_allowed)
				(footprints allowed)
			)
			(placement
				(enabled no)
				(sheetname "")
			)
			(fill
				(thermal_gap 0.5)
				(thermal_bridge_width 0.5)
				(island_removal_mode 0)
			)
			(polygon
				(pts
					(xy 270.512032 -8.6487) (xy 270.004032 -8.6487) (xy 270.004032 -7.6581) (xy 270.512032 -7.6581)
				)
			)
		)
	)
	(footprint ""
		(layer "B.Cu")
		(at 236.715808 -164.90188 -90)
		(property "Reference" "T1D15"
			(at 0 0 90)
			(layer "B.SilkS")
			(hide yes)
			(effects
				(font
					(size 1.27 1.27)
				)
				(justify mirror)
			)
		)
		(property "Value" "*"
			(at 3.4036 -4.46405 270)
			(unlocked yes)
			(layer "B.Fab")
			(hide yes)
			(effects
				(font
					(size 0.889 0.889)
					(thickness 0.1524)
				)
				(justify mirror)
			)
		)
		(property "Device Type" "TEST-PAD-12P-1-GP-U_DISCRET-GBA"
			(at 3.4036 -5.98805 270)
			(unlocked yes)
			(layer "B.Fab")
			(hide yes)
			(effects
				(font
					(size 0.889 0.889)
					(thickness 0.1524)
				)
				(justify mirror)
			)
		)
		(duplicate_pad_numbers_are_jumpers no)
		(fp_line
			(start -2.3622 3.4798)
			(end 2.3876 3.4798)
			(stroke
				(width 0.1524)
				(type default)
			)
			(layer "B.SilkS")
		)
		(fp_line
			(start 2.3876 3.4798)
			(end 2.3876 -4.826)
			(stroke
				(width 0.1524)
				(type default)
			)
			(layer "B.SilkS")
		)
		(fp_line
			(start -2.3622 -4.826)
			(end -2.3622 3.4798)
			(stroke
				(width 0.1524)
				(type default)
			)
			(layer "B.SilkS")
		)
		(fp_line
			(start 2.3876 -4.826)
			(end -2.3622 -4.826)
			(stroke
				(width 0.1524)
				(type default)
			)
			(layer "B.SilkS")
		)
		(fp_rect
			(start 2.6416 3.7338)
			(end -2.6162 -5.08)
			(stroke
				(width 0)
				(type default)
			)
			(fill no)
			(layer "B.CrtYd")
		)
		(fp_rect
			(start 2.6416 3.7338)
			(end -2.6162 -5.08)
			(stroke
				(width 0)
				(type default)
			)
			(fill no)
			(layer "B.Fab")
		)
		(pad "1" smd circle
			(at -0.496824 -1.301496 90)
			(size 0.6604 0.6604)
			(layers "B.Cu" "B.Mask" "B.Paste")
			(net "L3_85OHM_10INCH_DP")
		)
		(pad "2" smd circle
			(at 0.503936 -1.301496 90)
			(size 0.6604 0.6604)
			(layers "B.Cu" "B.Mask" "B.Paste")
			(net "L3_85OHM_10INCH_DN")
		)
		(pad "3" smd custom
			(at 0.00889 0.370078 90)
			(size 0.74295 0.74295)
			(layers "B.Cu" "B.Mask" "B.Paste")
			(net "GND")
			(options
				(clearance outline)
				(anchor circle)
			)
			(primitives
				(gr_poly
					(pts
						(xy -2.1209 -1.4859) (xy 2.1209 -1.4859) (xy 2.1209 1.4859) (xy 1.08585 1.4859) (xy 1.08585 0.4699)
						(xy -1.08585 0.4699) (xy -1.08585 1.4859) (xy -2.1209 1.4859)
					)
					(width 0)
					(fill yes)
				)
			)
		)
		(pad "4" thru_hole circle
			(at -1.266444 -3.851656 90)
			(size 1.4478 1.4478)
			(drill 1.0414)
			(layers "*.Cu" "*.Mask")
			(remove_unused_layers no)
			(net "GND")
			(clearance 0.1524)
			(thermal_gap 0.1524)
		)
		(pad "5" thru_hole circle
			(at 1.273556 -3.851656 90)
			(size 1.4478 1.4478)
			(drill 1.0414)
			(layers "*.Cu" "*.Mask")
			(remove_unused_layers no)
			(net "GND")
			(clearance 0.1524)
			(thermal_gap 0.1524)
		)
		(pad "6" thru_hole circle
			(at -1.266444 2.498344 90)
			(size 1.4478 1.4478)
			(drill 1.0414)
			(layers "*.Cu" "*.Mask")
			(remove_unused_layers no)
			(net "GND")
			(clearance 0.1524)
			(thermal_gap 0.1524)
		)
		(pad "7" thru_hole circle
			(at 1.273556 2.498344 90)
			(size 1.4478 1.4478)
			(drill 1.0414)
			(layers "*.Cu" "*.Mask")
			(remove_unused_layers no)
			(net "GND")
			(clearance 0.1524)
			(thermal_gap 0.1524)
		)
		(pad "8" thru_hole circle
			(at -1.27 -0.4572 90)
			(size 0.7112 0.7112)
			(drill 0.4064)
			(layers "*.Cu" "*.Mask")
			(remove_unused_layers no)
			(net "GND")
			(clearance 0.1016)
			(thermal_gap 0.1016)
		)
		(pad "9" thru_hole circle
			(at -1.27 0.762 90)
			(size 0.7112 0.7112)
			(drill 0.4064)
			(layers "*.Cu" "*.Mask")
			(remove_unused_layers no)
			(net "GND")
			(clearance 0.1016)
			(thermal_gap 0.1016)
		)
		(pad "10" thru_hole circle
			(at 0.0254 0.762 90)
			(size 0.7112 0.7112)
			(drill 0.4064)
			(layers "*.Cu" "*.Mask")
			(remove_unused_layers no)
			(net "GND")
			(clearance 0.1016)
			(thermal_gap 0.1016)
		)
		(pad "11" thru_hole circle
			(at 1.27 0.762 90)
			(size 0.7112 0.7112)
			(drill 0.4064)
			(layers "*.Cu" "*.Mask")
			(remove_unused_layers no)
			(net "GND")
			(clearance 0.1016)
			(thermal_gap 0.1016)
		)
		(pad "12" thru_hole circle
			(at 1.27 -0.4572 90)
			(size 0.7112 0.7112)
			(drill 0.4064)
			(layers "*.Cu" "*.Mask")
			(remove_unused_layers no)
			(net "GND")
			(clearance 0.1016)
			(thermal_gap 0.1016)
		)
	)
)
